# T6G (Grand Teton) — schematic netlist excerpt (pin names and nets, part order shuffled) for the footprints in the layout excerpt that follows; sources: Cadence DE-HDL packaged netlist, KiCad conversion of 04192023_DAF0TMB3IC0_F0TG_MB_C_brd_V02_OCP.brd

R4151  Q_RES  33.2 1% CHIP  pkg 0402LF  page 151 : A = SMB_1_PLD_3V3AUX_SCL ; B = SMB_2_PLD_3V3AUX_SCL_R1
R1189  Q_RES  1K 1% CHIP  pkg 0402LF  page 83 : A = PVDD11_S3_P0_PMALERT ; B = P3V3_AUX

(kicad_pcb
	(version 20260206)
	(generator "pcbnew")
	(generator_version "10.0")
	(general
		(thickness 1.6)
		(legacy_teardrops no)
	)
	(paper "A4")
	(title_block
		(title "04192023_DAF0TMB3IC0_F0TG_MB_C_brd_V02_OCP.brd")
		(comment 1 "Grand Teton / footprints 6900-6901 of 8354")
	)
	(layers
		(0 "F.Cu" signal "TOP")
		(4 "In1.Cu" signal "GND")
		(6 "In2.Cu" signal "IN1")
		(8 "In3.Cu" signal "GND1")
		(10 "In4.Cu" signal "IN2")
		(12 "In5.Cu" signal "GND2")
		(14 "In6.Cu" signal "IN3")
		(16 "In7.Cu" signal "GND3")
		(18 "In8.Cu" signal "VCC")
		(20 "In9.Cu" signal "VCC1")
		(22 "In10.Cu" signal "GND4")
		(24 "In11.Cu" signal "IN4")
		(26 "In12.Cu" signal "GND5")
		(28 "In13.Cu" signal "IN5")
		(30 "In14.Cu" signal "GND6")
		(32 "In15.Cu" signal "IN6")
		(34 "In16.Cu" signal "GND7")
		(2 "B.Cu" signal "BOTTOM")
		(9 "F.Adhes" user "F.Adhesive")
		(11 "B.Adhes" user "B.Adhesive")
		(13 "F.Paste" user "Package Geometry/Pastemask Top")
		(15 "B.Paste" user "Package Geometry/Pastemask Bottom")
		(5 "F.SilkS" user "Ref Des/Silkscreen Top")
		(7 "B.SilkS" user "Ref Des/Silkscreen Bottom")
		(1 "F.Mask" user "Board Geometry/Soldermask Top")
		(3 "B.Mask" user "Board Geometry/Soldermask Bottom")
		(17 "Dwgs.User" user "User.Drawings")
		(19 "Cmts.User" user "User.Comments")
		(21 "Eco1.User" user "User.Eco1")
		(23 "Eco2.User" user "User.Eco2")
		(25 "Edge.Cuts" user "Board Geometry/Outline")
		(27 "Margin" user)
		(31 "F.CrtYd" user "Package Geometry/Place Bound Top")
		(29 "B.CrtYd" user "Package Geometry/Place Bound Bottom")
		(35 "F.Fab" user "Ref Des/Assembly Top")
		(33 "B.Fab" user "Ref Des/Assembly Bottom")
	)
	(footprint ""
		(layer "B.Cu")
		(at 162.46983 -16.77416 180)
		(property "Reference" "R4151"
			(at 0 0 0)
			(layer "B.SilkS")
			(hide yes)
			(effects
				(font
					(size 1.27 1.27)
				)
				(justify mirror)
			)
		)
		(property "Value" ""
			(at 0 0 0)
			(layer "B.Fab")
			(effects
				(font
					(size 1.27 1.27)
				)
				(justify mirror)
			)
		)
		(duplicate_pad_numbers_are_jumpers no)
		(fp_line
			(start 0.7874 0.4064)
			(end 0.7874 -0.4064)
			(stroke
				(width 0.1524)
				(type default)
			)
			(layer "B.SilkS")
		)
		(fp_line
			(start 0.7874 -0.4064)
			(end -0.7874 -0.4064)
			(stroke
				(width 0.1524)
				(type default)
			)
			(layer "B.SilkS")
		)
		(fp_line
			(start -0.7874 0.4064)
			(end 0.7874 0.4064)
			(stroke
				(width 0.1524)
				(type default)
			)
			(layer "B.SilkS")
		)
		(fp_line
			(start -0.7874 -0.4064)
			(end -0.7874 0.4064)
			(stroke
				(width 0.1524)
				(type default)
			)
			(layer "B.SilkS")
		)
		(fp_line
			(start 0.67945 0.3048)
			(end 0.67945 -0.305054)
			(stroke
				(width 0.1)
				(type default)
			)
			(layer "B.Fab")
		)
		(fp_line
			(start 0.67945 -0.305054)
			(end 0.12065 -0.305054)
			(stroke
				(width 0.1)
				(type default)
			)
			(layer "B.Fab")
		)
		(fp_line
			(start 0.12065 0.3048)
			(end 0.67945 0.3048)
			(stroke
				(width 0.1)
				(type default)
			)
			(layer "B.Fab")
		)
		(fp_line
			(start 0.12065 0.2794)
			(end 0.12065 0.3048)
			(stroke
				(width 0.1)
				(type default)
			)
			(layer "B.Fab")
		)
		(fp_line
			(start 0.12065 -0.2794)
			(end -0.12065 -0.2794)
			(stroke
				(width 0.1)
				(type default)
			)
			(layer "B.Fab")
		)
		(fp_line
			(start 0.12065 -0.305054)
			(end 0.12065 -0.2794)
			(stroke
				(width 0.1)
				(type default)
			)
			(layer "B.Fab")
		)
		(fp_line
			(start -0.120396 0.3048)
			(end -0.120396 0.2794)
			(stroke
				(width 0.1)
				(type default)
			)
			(layer "B.Fab")
		)
		(fp_line
			(start -0.120396 0.2794)
			(end 0.12065 0.2794)
			(stroke
				(width 0.1)
				(type default)
			)
			(layer "B.Fab")
		)
		(fp_line
			(start -0.12065 -0.2794)
			(end -0.12065 -0.3048)
			(stroke
				(width 0.1)
				(type default)
			)
			(layer "B.Fab")
		)
		(fp_line
			(start -0.12065 -0.3048)
			(end -0.67945 -0.3048)
			(stroke
				(width 0.1)
				(type default)
			)
			(layer "B.Fab")
		)
		(fp_line
			(start -0.67945 0.3048)
			(end -0.120396 0.3048)
			(stroke
				(width 0.1)
				(type default)
			)
			(layer "B.Fab")
		)
		(fp_line
			(start -0.67945 -0.3048)
			(end -0.67945 0.3048)
			(stroke
				(width 0.1)
				(type default)
			)
			(layer "B.Fab")
		)
		(pad "1" smd circle
			(at 0.40005 0)
			(size 0 0)
			(layers "B.Cu" "B.Mask" "B.Paste")
			(net "SMB_1_PLD_3V3AUX_SCL")
		)
		(pad "2" smd circle
			(at -0.40005 0)
			(size 0 0)
			(layers "B.Cu" "B.Mask" "B.Paste")
			(net "SMB_2_PLD_3V3AUX_SCL_R1")
		)
	)
	(footprint ""
		(layer "B.Cu")
		(at 185.458608 -111.466376 -90)
		(property "Reference" "R1189"
			(at 0 0 90)
			(layer "B.SilkS")
			(hide yes)
			(effects
				(font
					(size 1.27 1.27)
				)
				(justify mirror)
			)
		)
		(property "Value" ""
			(at 0 0 90)
			(layer "B.Fab")
			(effects
				(font
					(size 1.27 1.27)
				)
				(justify mirror)
			)
		)
		(duplicate_pad_numbers_are_jumpers no)
		(fp_line
			(start -0.7874 0.4064)
			(end 0.7874 0.4064)
			(stroke
				(width 0.1524)
				(type default)
			)
			(layer "B.SilkS")
		)
		(fp_line
			(start 0.7874 0.4064)
			(end 0.7874 -0.4064)
			(stroke
				(width 0.1524)
				(type default)
			)
			(layer "B.SilkS")
		)
		(fp_line
			(start -0.7874 -0.4064)
			(end -0.7874 0.4064)
			(stroke
				(width 0.1524)
				(type default)
			)
			(layer "B.SilkS")
		)
		(fp_line
			(start 0.7874 -0.4064)
			(end -0.7874 -0.4064)
			(stroke
				(width 0.1524)
				(type default)
			)
			(layer "B.SilkS")
		)
		(fp_line
			(start -0.67945 0.3048)
			(end -0.120396 0.3048)
			(stroke
				(width 0.1)
				(type default)
			)
			(layer "B.Fab")
		)
		(fp_line
			(start -0.120396 0.3048)
			(end -0.120396 0.2794)
			(stroke
				(width 0.1)
				(type default)
			)
			(layer "B.Fab")
		)
		(fp_line
			(start 0.12065 0.3048)
			(end 0.67945 0.3048)
			(stroke
				(width 0.1)
				(type default)
			)
			(layer "B.Fab")
		)
		(fp_line
			(start 0.67945 0.3048)
			(end 0.67945 -0.305054)
			(stroke
				(width 0.1)
				(type default)
			)
			(layer "B.Fab")
		)
		(fp_line
			(start -0.120396 0.2794)
			(end 0.12065 0.2794)
			(stroke
				(width 0.1)
				(type default)
			)
			(layer "B.Fab")
		)
		(fp_line
			(start 0.12065 0.2794)
			(end 0.12065 0.3048)
			(stroke
				(width 0.1)
				(type default)
			)
			(layer "B.Fab")
		)
		(fp_line
			(start -0.12065 -0.2794)
			(end -0.12065 -0.3048)
			(stroke
				(width 0.1)
				(type default)
			)
			(layer "B.Fab")
		)
		(fp_line
			(start 0.12065 -0.2794)
			(end -0.12065 -0.2794)
			(stroke
				(width 0.1)
				(type default)
			)
			(layer "B.Fab")
		)
		(fp_line
			(start -0.67945 -0.3048)
			(end -0.67945 0.3048)
			(stroke
				(width 0.1)
				(type default)
			)
			(layer "B.Fab")
		)
		(fp_line
			(start -0.12065 -0.3048)
			(end -0.67945 -0.3048)
			(stroke
				(width 0.1)
				(type default)
			)
			(layer "B.Fab")
		)
		(fp_line
			(start 0.12065 -0.305054)
			(end 0.12065 -0.2794)
			(stroke
				(width 0.1)
				(type default)
			)
			(layer "B.Fab")
		)
		(fp_line
			(start 0.67945 -0.305054)
			(end 0.12065 -0.305054)
			(stroke
				(width 0.1)
				(type default)
			)
			(layer "B.Fab")
		)
		(pad "1" smd circle
			(at 0.40005 0 90)
			(size 0 0)
			(layers "B.Cu" "B.Mask" "B.Paste")
			(net "PVDD11_S3_P0_PMALERT")
		)
		(pad "2" smd circle
			(at -0.40005 0 90)
			(size 0 0)
			(layers "B.Cu" "B.Mask" "B.Paste")
			(net "P3V3_AUX")
		)
	)
)
